# T6G (Grand Teton) — schematic netlist excerpt (pin names and nets, part order shuffled) for the footprints in the layout excerpt that follows; sources: Cadence DE-HDL packaged netlist, KiCad conversion of 04192023_DAF0TMB3IC0_F0TG_MB_C_brd_V02_OCP.brd

C645  Q_CAP  10UF 6.3V 20% X6S  pkg C0402  page 290 : A = P0V9_CPU0_RT1_2A ; B = GND
PC513_1  Q_CAP  22UF 16V 20% X6S  pkg C0805  page 225 : A = SW_P12V_AUX_PVDD11_S3_P1_FLT ; B = GND
R6107  Q_RES  10K 5% CHIP  pkg 0402LF  page 167 : A = PVDD18_S5_P0 ; B = BIOS_DEBUG_MODE

(kicad_pcb
	(version 20260206)
	(generator "pcbnew")
	(generator_version "10.0")
	(general
		(thickness 1.6)
		(legacy_teardrops no)
	)
	(paper "A4")
	(title_block
		(title "04192023_DAF0TMB3IC0_F0TG_MB_C_brd_V02_OCP.brd")
		(comment 1 "Grand Teton / footprints 7292-7294 of 8354")
	)
	(layers
		(0 "F.Cu" signal "TOP")
		(4 "In1.Cu" signal "GND")
		(6 "In2.Cu" signal "IN1")
		(8 "In3.Cu" signal "GND1")
		(10 "In4.Cu" signal "IN2")
		(12 "In5.Cu" signal "GND2")
		(14 "In6.Cu" signal "IN3")
		(16 "In7.Cu" signal "GND3")
		(18 "In8.Cu" signal "VCC")
		(20 "In9.Cu" signal "VCC1")
		(22 "In10.Cu" signal "GND4")
		(24 "In11.Cu" signal "IN4")
		(26 "In12.Cu" signal "GND5")
		(28 "In13.Cu" signal "IN5")
		(30 "In14.Cu" signal "GND6")
		(32 "In15.Cu" signal "IN6")
		(34 "In16.Cu" signal "GND7")
		(2 "B.Cu" signal "BOTTOM")
		(9 "F.Adhes" user "F.Adhesive")
		(11 "B.Adhes" user "B.Adhesive")
		(13 "F.Paste" user "Package Geometry/Pastemask Top")
		(15 "B.Paste" user "Package Geometry/Pastemask Bottom")
		(5 "F.SilkS" user "Ref Des/Silkscreen Top")
		(7 "B.SilkS" user "Ref Des/Silkscreen Bottom")
		(1 "F.Mask" user "Board Geometry/Soldermask Top")
		(3 "B.Mask" user "Board Geometry/Soldermask Bottom")
		(17 "Dwgs.User" user "User.Drawings")
		(19 "Cmts.User" user "User.Comments")
		(21 "Eco1.User" user "User.Eco1")
		(23 "Eco2.User" user "User.Eco2")
		(25 "Edge.Cuts" user "Board Geometry/Outline")
		(27 "Margin" user)
		(31 "F.CrtYd" user "Package Geometry/Place Bound Top")
		(29 "B.CrtYd" user "Package Geometry/Place Bound Bottom")
		(35 "F.Fab" user "Ref Des/Assembly Top")
		(33 "B.Fab" user "Ref Des/Assembly Bottom")
	)
	(footprint ""
		(layer "B.Cu")
		(at 183.946292 -351.21342 90)
		(property "Reference" "PC513_1"
			(at 0 0 90)
			(layer "B.SilkS")
			(hide yes)
			(effects
				(font
					(size 1.27 1.27)
				)
				(justify mirror)
			)
		)
		(property "Value" ""
			(at 0 0 90)
			(layer "B.Fab")
			(effects
				(font
					(size 1.27 1.27)
				)
				(justify mirror)
			)
		)
		(duplicate_pad_numbers_are_jumpers no)
		(fp_line
			(start 1.524 -0.762)
			(end -1.524 -0.762)
			(stroke
				(width 0.1524)
				(type default)
			)
			(layer "B.SilkS")
		)
		(fp_line
			(start -1.524 -0.762)
			(end -1.524 0.762)
			(stroke
				(width 0.1524)
				(type default)
			)
			(layer "B.SilkS")
		)
		(fp_line
			(start 1.524 0.762)
			(end 1.524 -0.762)
			(stroke
				(width 0.1524)
				(type default)
			)
			(layer "B.SilkS")
		)
		(fp_line
			(start -1.524 0.762)
			(end 1.524 0.762)
			(stroke
				(width 0.1524)
				(type default)
			)
			(layer "B.SilkS")
		)
		(fp_line
			(start 1.1049 -0.724916)
			(end 1.1049 0.724916)
			(stroke
				(width 0.1)
				(type default)
			)
			(layer "B.Fab")
		)
		(fp_line
			(start -1.1049 -0.724916)
			(end 1.1049 -0.724916)
			(stroke
				(width 0.1)
				(type default)
			)
			(layer "B.Fab")
		)
		(fp_line
			(start 1.1049 0.724916)
			(end -1.1049 0.724916)
			(stroke
				(width 0.1)
				(type default)
			)
			(layer "B.Fab")
		)
		(fp_line
			(start -1.1049 0.724916)
			(end -1.1049 -0.724916)
			(stroke
				(width 0.1)
				(type default)
			)
			(layer "B.Fab")
		)
		(pad "1" smd rect
			(at 0.889 0 90)
			(size 1.016 1.27)
			(layers "B.Cu" "B.Mask" "B.Paste")
			(net "SW_P12V_AUX_PVDD11_S3_P1_FLT")
		)
		(pad "2" smd rect
			(at -0.889 0 90)
			(size 1.016 1.27)
			(layers "B.Cu" "B.Mask" "B.Paste")
			(net "GND")
		)
	)
	(footprint ""
		(layer "B.Cu")
		(at 428.98695 -37.023548 180)
		(property "Reference" "R6107"
			(at 0 0 0)
			(layer "B.SilkS")
			(hide yes)
			(effects
				(font
					(size 1.27 1.27)
				)
				(justify mirror)
			)
		)
		(property "Value" ""
			(at 0 0 0)
			(layer "B.Fab")
			(effects
				(font
					(size 1.27 1.27)
				)
				(justify mirror)
			)
		)
		(duplicate_pad_numbers_are_jumpers no)
		(fp_line
			(start 0.7874 0.4064)
			(end 0.7874 -0.4064)
			(stroke
				(width 0.1524)
				(type default)
			)
			(layer "B.SilkS")
		)
		(fp_line
			(start 0.7874 -0.4064)
			(end -0.7874 -0.4064)
			(stroke
				(width 0.1524)
				(type default)
			)
			(layer "B.SilkS")
		)
		(fp_line
			(start -0.7874 0.4064)
			(end 0.7874 0.4064)
			(stroke
				(width 0.1524)
				(type default)
			)
			(layer "B.SilkS")
		)
		(fp_line
			(start -0.7874 -0.4064)
			(end -0.7874 0.4064)
			(stroke
				(width 0.1524)
				(type default)
			)
			(layer "B.SilkS")
		)
		(fp_line
			(start 0.67945 0.3048)
			(end 0.67945 -0.305054)
			(stroke
				(width 0.1)
				(type default)
			)
			(layer "B.Fab")
		)
		(fp_line
			(start 0.67945 -0.305054)
			(end 0.12065 -0.305054)
			(stroke
				(width 0.1)
				(type default)
			)
			(layer "B.Fab")
		)
		(fp_line
			(start 0.12065 0.3048)
			(end 0.67945 0.3048)
			(stroke
				(width 0.1)
				(type default)
			)
			(layer "B.Fab")
		)
		(fp_line
			(start 0.12065 0.2794)
			(end 0.12065 0.3048)
			(stroke
				(width 0.1)
				(type default)
			)
			(layer "B.Fab")
		)
		(fp_line
			(start 0.12065 -0.2794)
			(end -0.12065 -0.2794)
			(stroke
				(width 0.1)
				(type default)
			)
			(layer "B.Fab")
		)
		(fp_line
			(start 0.12065 -0.305054)
			(end 0.12065 -0.2794)
			(stroke
				(width 0.1)
				(type default)
			)
			(layer "B.Fab")
		)
		(fp_line
			(start -0.120396 0.3048)
			(end -0.120396 0.2794)
			(stroke
				(width 0.1)
				(type default)
			)
			(layer "B.Fab")
		)
		(fp_line
			(start -0.120396 0.2794)
			(end 0.12065 0.2794)
			(stroke
				(width 0.1)
				(type default)
			)
			(layer "B.Fab")
		)
		(fp_line
			(start -0.12065 -0.2794)
			(end -0.12065 -0.3048)
			(stroke
				(width 0.1)
				(type default)
			)
			(layer "B.Fab")
		)
		(fp_line
			(start -0.12065 -0.3048)
			(end -0.67945 -0.3048)
			(stroke
				(width 0.1)
				(type default)
			)
			(layer "B.Fab")
		)
		(fp_line
			(start -0.67945 0.3048)
			(end -0.120396 0.3048)
			(stroke
				(width 0.1)
				(type default)
			)
			(layer "B.Fab")
		)
		(fp_line
			(start -0.67945 -0.3048)
			(end -0.67945 0.3048)
			(stroke
				(width 0.1)
				(type default)
			)
			(layer "B.Fab")
		)
		(pad "1" smd circle
			(at 0.40005 0)
			(size 0 0)
			(layers "B.Cu" "B.Mask" "B.Paste")
			(net "PVDD18_S5_P0")
		)
		(pad "2" smd circle
			(at -0.40005 0)
			(size 0 0)
			(layers "B.Cu" "B.Mask" "B.Paste")
			(net "BIOS_DEBUG_MODE")
		)
	)
	(footprint ""
		(layer "B.Cu")
		(at 335.918556 -398.942052 90)
		(property "Reference" "C645"
			(at 0 0 90)
			(layer "B.SilkS")
			(hide yes)
			(effects
				(font
					(size 1.27 1.27)
				)
				(justify mirror)
			)
		)
		(property "Value" ""
			(at 0 0 90)
			(layer "B.Fab")
			(effects
				(font
					(size 1.27 1.27)
				)
				(justify mirror)
			)
		)
		(duplicate_pad_numbers_are_jumpers no)
		(fp_line
			(start 0.7874 -0.4064)
			(end -0.7874 -0.4064)
			(stroke
				(width 0.1524)
				(type default)
			)
			(layer "B.SilkS")
		)
		(fp_line
			(start -0.7874 -0.4064)
			(end -0.7874 0.4064)
			(stroke
				(width 0.1524)
				(type default)
			)
			(layer "B.SilkS")
		)
		(fp_line
			(start 0.7874 0.4064)
			(end 0.7874 -0.4064)
			(stroke
				(width 0.1524)
				(type default)
			)
			(layer "B.SilkS")
		)
		(fp_line
			(start -0.7874 0.4064)
			(end 0.7874 0.4064)
			(stroke
				(width 0.1524)
				(type default)
			)
			(layer "B.SilkS")
		)
		(fp_line
			(start 0.67945 -0.305054)
			(end 0.12065 -0.305054)
			(stroke
				(width 0.1)
				(type default)
			)
			(layer "B.Fab")
		)
		(fp_line
			(start 0.12065 -0.305054)
			(end 0.12065 -0.2794)
			(stroke
				(width 0.1)
				(type default)
			)
			(layer "B.Fab")
		)
		(fp_line
			(start -0.12065 -0.3048)
			(end -0.67945 -0.3048)
			(stroke
				(width 0.1)
				(type default)
			)
			(layer "B.Fab")
		)
		(fp_line
			(start -0.67945 -0.3048)
			(end -0.67945 0.3048)
			(stroke
				(width 0.1)
				(type default)
			)
			(layer "B.Fab")
		)
		(fp_line
			(start 0.12065 -0.2794)
			(end -0.12065 -0.2794)
			(stroke
				(width 0.1)
				(type default)
			)
			(layer "B.Fab")
		)
		(fp_line
			(start -0.12065 -0.2794)
			(end -0.12065 -0.3048)
			(stroke
				(width 0.1)
				(type default)
			)
			(layer "B.Fab")
		)
		(fp_line
			(start 0.12065 0.2794)
			(end 0.12065 0.3048)
			(stroke
				(width 0.1)
				(type default)
			)
			(layer "B.Fab")
		)
		(fp_line
			(start -0.120396 0.2794)
			(end 0.12065 0.2794)
			(stroke
				(width 0.1)
				(type default)
			)
			(layer "B.Fab")
		)
		(fp_line
			(start 0.67945 0.3048)
			(end 0.67945 -0.305054)
			(stroke
				(width 0.1)
				(type default)
			)
			(layer "B.Fab")
		)
		(fp_line
			(start 0.12065 0.3048)
			(end 0.67945 0.3048)
			(stroke
				(width 0.1)
				(type default)
			)
			(layer "B.Fab")
		)
		(fp_line
			(start -0.120396 0.3048)
			(end -0.120396 0.2794)
			(stroke
				(width 0.1)
				(type default)
			)
			(layer "B.Fab")
		)
		(fp_line
			(start -0.67945 0.3048)
			(end -0.120396 0.3048)
			(stroke
				(width 0.1)
				(type default)
			)
			(layer "B.Fab")
		)
		(pad "1" smd circle
			(at 0.40005 0 270)
			(size 0 0)
			(layers "B.Cu" "B.Mask" "B.Paste")
			(net "P0V9_CPU0_RT1_2A")
		)
		(pad "2" smd circle
			(at -0.40005 0 270)
			(size 0 0)
			(layers "B.Cu" "B.Mask" "B.Paste")
			(net "GND")
		)
	)
)
